(kicad_pcb
	(version 20260206)
	(generator "pcbnew")
	(generator_version "10.0")
	(general
		(thickness 1.6)
		(legacy_teardrops no)
	)
	(paper "A4")
	(title_block
		(title "panther-plus-userver — 13130-1b_20150205.brd")
		(comment 1 "Honey Badger (Wiwynn) / footprints 966-973 of 1509")
	)
	(layers
		(0 "F.Cu" signal "TOP")
		(4 "In1.Cu" signal "L2")
		(6 "In2.Cu" signal "L3")
		(8 "In3.Cu" signal "L4")
		(10 "In4.Cu" signal "L5")
		(12 "In5.Cu" signal "L6")
		(14 "In6.Cu" signal "L7")
		(16 "In7.Cu" signal "L8")
		(18 "In8.Cu" signal "L9")
		(20 "In9.Cu" signal "L10")
		(22 "In10.Cu" signal "L11")
		(2 "B.Cu" signal "BOTTOM")
		(9 "F.Adhes" user "F.Adhesive")
		(11 "B.Adhes" user "B.Adhesive")
		(13 "F.Paste" user "Package Geometry/Pastemask Top")
		(15 "B.Paste" user "Package Geometry/Pastemask Bottom")
		(5 "F.SilkS" user "Ref Des/Silkscreen Top")
		(7 "B.SilkS" user "Ref Des/Silkscreen Bottom")
		(1 "F.Mask" user "Board Geometry/Soldermask Top")
		(3 "B.Mask" user "Board Geometry/Soldermask Bottom")
		(17 "Dwgs.User" user "User.Drawings")
		(19 "Cmts.User" user "User.Comments")
		(21 "Eco1.User" user "User.Eco1")
		(23 "Eco2.User" user "User.Eco2")
		(25 "Edge.Cuts" user "Board Geometry/Outline")
		(27 "Margin" user)
		(31 "F.CrtYd" user "Package Geometry/Place Bound Top")
		(29 "B.CrtYd" user "Package Geometry/Place Bound Bottom")
		(35 "F.Fab" user "Ref Des/Assembly Top")
		(33 "B.Fab" user "Ref Des/Assembly Bottom")
	)
	(footprint ""
		(layer "B.Cu")
		(at 197.4596 -63.3222 -90)
		(property "Reference" "PC158"
			(at 0 0 90)
			(layer "B.SilkS")
			(hide yes)
			(effects
				(font
					(size 1.27 1.27)
				)
				(justify mirror)
			)
		)
		(property "Value" "SC10U6D3V3MX-GP"
			(at 0.0254 -2.0193 270)
			(unlocked yes)
			(layer "B.Fab")
			(hide yes)
			(effects
				(font
					(size 1.016 1.016)
					(thickness 0.1524)
				)
				(justify mirror)
			)
		)
		(property "Device Type" "C603H38"
			(at 0.0254 -3.5433 270)
			(unlocked yes)
			(layer "B.Fab")
			(hide yes)
			(effects
				(font
					(size 1.016 1.016)
					(thickness 0.1524)
				)
				(justify mirror)
			)
		)
		(duplicate_pad_numbers_are_jumpers no)
		(fp_line
			(start 0.4064 0)
			(end -0.4064 0)
			(stroke
				(width 0.2286)
				(type default)
			)
			(layer "B.SilkS")
		)
		(fp_rect
			(start 0.635 1.1811)
			(end -0.635 -1.1811)
			(stroke
				(width 0)
				(type default)
			)
			(fill no)
			(layer "B.CrtYd")
		)
		(fp_rect
			(start 0.635 1.1811)
			(end -0.635 -1.1811)
			(stroke
				(width 0)
				(type default)
			)
			(fill no)
			(layer "B.Fab")
		)
		(pad "1" smd custom
			(at 0 -0.6604 90)
			(size 0.19685 0.19685)
			(layers "B.Cu" "B.Mask" "B.Paste")
			(net "PV_VDDR")
			(options
				(clearance outline)
				(anchor circle)
			)
			(primitives
				(gr_poly
					(pts
						(arc
							(start 0.508 0.2921)
							(mid 0.478242 0.363942)
							(end 0.4064 0.3937)
						)
						(arc
							(start -0.4064 0.3937)
							(mid -0.478242 0.363942)
							(end -0.508 0.2921)
						)
						(arc
							(start -0.508 -0.2921)
							(mid -0.478242 -0.363942)
							(end -0.4064 -0.3937)
						)
						(arc
							(start 0.4064 -0.3937)
							(mid 0.478242 -0.363942)
							(end 0.508 -0.2921)
						)
					)
					(width 0)
					(fill yes)
				)
			)
		)
		(pad "2" smd custom
			(at 0 0.6604 90)
			(size 0.19685 0.19685)
			(layers "B.Cu" "B.Mask" "B.Paste")
			(net "GND")
			(options
				(clearance outline)
				(anchor circle)
			)
			(primitives
				(gr_poly
					(pts
						(arc
							(start 0.508 0.2921)
							(mid 0.478242 0.363942)
							(end 0.4064 0.3937)
						)
						(arc
							(start -0.4064 0.3937)
							(mid -0.478242 0.363942)
							(end -0.508 0.2921)
						)
						(arc
							(start -0.508 -0.2921)
							(mid -0.478242 -0.363942)
							(end -0.4064 -0.3937)
						)
						(arc
							(start 0.4064 -0.3937)
							(mid 0.478242 -0.363942)
							(end 0.508 -0.2921)
						)
					)
					(width 0)
					(fill yes)
				)
			)
		)
	)
	(footprint ""
		(layer "B.Cu")
		(at 104.3686 -66.7512 -90)
		(property "Reference" "PR5"
			(at 0 0 90)
			(layer "B.SilkS")
			(hide yes)
			(effects
				(font
					(size 1.27 1.27)
				)
				(justify mirror)
			)
		)
		(property "Value" "0R2J-2-GP"
			(at -1.7907 -1.1176 270)
			(unlocked yes)
			(layer "B.Fab")
			(hide yes)
			(effects
				(font
					(size 1.016 1.016)
					(thickness 0.1524)
				)
				(justify mirror)
			)
		)
		(property "Device Type" "R402H16"
			(at -1.7907 -2.6416 270)
			(unlocked yes)
			(layer "B.Fab")
			(hide yes)
			(effects
				(font
					(size 1.016 1.016)
					(thickness 0.1524)
				)
				(justify mirror)
			)
		)
		(duplicate_pad_numbers_are_jumpers no)
		(fp_rect
			(start 0.381 0.8382)
			(end -0.381 -0.8382)
			(stroke
				(width 0)
				(type default)
			)
			(fill no)
			(layer "B.CrtYd")
		)
		(fp_rect
			(start 0.381 0.8382)
			(end -0.381 -0.8382)
			(stroke
				(width 0)
				(type default)
			)
			(fill no)
			(layer "B.Fab")
		)
		(pad "1" smd custom
			(at 0 -0.4318 90)
			(size 0.127 0.127)
			(layers "B.Cu" "B.Mask" "B.Paste")
			(net "VCCRAMCPUSI1_SENSE")
			(options
				(clearance outline)
				(anchor circle)
			)
			(primitives
				(gr_poly
					(pts
						(arc
							(start -0.2032 0.2794)
							(mid -0.239121 0.264521)
							(end -0.254 0.2286)
						)
						(arc
							(start -0.254 -0.2286)
							(mid -0.239121 -0.264521)
							(end -0.2032 -0.2794)
						)
						(arc
							(start 0.2032 -0.2794)
							(mid 0.239121 -0.264521)
							(end 0.254 -0.2286)
						)
						(arc
							(start 0.254 0.2286)
							(mid 0.239121 0.264521)
							(end 0.2032 0.2794)
						)
					)
					(width 0)
					(fill yes)
				)
			)
		)
		(pad "2" smd custom
			(at 0 0.4318 90)
			(size 0.127 0.127)
			(layers "B.Cu" "B.Mask" "B.Paste")
			(net "VR_P1V1_VFBR")
			(options
				(clearance outline)
				(anchor circle)
			)
			(primitives
				(gr_poly
					(pts
						(arc
							(start -0.2032 0.2794)
							(mid -0.239121 0.264521)
							(end -0.254 0.2286)
						)
						(arc
							(start -0.254 -0.2286)
							(mid -0.239121 -0.264521)
							(end -0.2032 -0.2794)
						)
						(arc
							(start 0.2032 -0.2794)
							(mid 0.239121 -0.264521)
							(end 0.254 -0.2286)
						)
						(arc
							(start 0.254 0.2286)
							(mid 0.239121 0.264521)
							(end 0.2032 0.2794)
						)
					)
					(width 0)
					(fill yes)
				)
			)
		)
	)
	(footprint ""
		(layer "B.Cu")
		(at 92.71 -37.592)
		(property "Reference" "C182"
			(at 0 0 0)
			(layer "B.SilkS")
			(hide yes)
			(effects
				(font
					(size 1.27 1.27)
				)
				(justify mirror)
			)
		)
		(property "Value" "SC1U10V2KX-1GP"
			(at -1.1811 -2.7051 0)
			(unlocked yes)
			(layer "B.Fab")
			(hide yes)
			(effects
				(font
					(size 1.016 1.016)
					(thickness 0.1524)
				)
				(justify mirror)
			)
		)
		(property "Device Type" "C402H22"
			(at -1.1811 -4.2291 0)
			(unlocked yes)
			(layer "B.Fab")
			(hide yes)
			(effects
				(font
					(size 1.016 1.016)
					(thickness 0.1524)
				)
				(justify mirror)
			)
		)
		(duplicate_pad_numbers_are_jumpers no)
		(fp_rect
			(start 0.381 0.7366)
			(end -0.381 -0.7366)
			(stroke
				(width 0)
				(type default)
			)
			(fill no)
			(layer "B.CrtYd")
		)
		(fp_rect
			(start 0.381 0.7366)
			(end -0.381 -0.7366)
			(stroke
				(width 0)
				(type default)
			)
			(fill no)
			(layer "B.Fab")
		)
		(pad "1" smd custom
			(at 0 -0.4572 180)
			(size 0.1143 0.1143)
			(layers "B.Cu" "B.Mask" "B.Paste")
			(net "P1V0")
			(options
				(clearance outline)
				(anchor circle)
			)
			(primitives
				(gr_poly
					(pts
						(arc
							(start -0.254 0.1778)
							(mid -0.239121 0.213721)
							(end -0.2032 0.2286)
						)
						(arc
							(start 0.2032 0.2286)
							(mid 0.239121 0.213721)
							(end 0.254 0.1778)
						)
						(arc
							(start 0.254 -0.1778)
							(mid 0.239121 -0.213721)
							(end 0.2032 -0.2286)
						)
						(arc
							(start -0.2032 -0.2286)
							(mid -0.239121 -0.213721)
							(end -0.254 -0.1778)
						)
					)
					(width 0)
					(fill yes)
				)
			)
		)
		(pad "2" smd custom
			(at 0 0.4572 180)
			(size 0.1143 0.1143)
			(layers "B.Cu" "B.Mask" "B.Paste")
			(net "GND")
			(options
				(clearance outline)
				(anchor circle)
			)
			(primitives
				(gr_poly
					(pts
						(arc
							(start -0.254 0.1778)
							(mid -0.239121 0.213721)
							(end -0.2032 0.2286)
						)
						(arc
							(start 0.2032 0.2286)
							(mid 0.239121 0.213721)
							(end 0.254 0.1778)
						)
						(arc
							(start 0.254 -0.1778)
							(mid 0.239121 -0.213721)
							(end 0.2032 -0.2286)
						)
						(arc
							(start -0.2032 -0.2286)
							(mid -0.239121 -0.213721)
							(end -0.254 -0.1778)
						)
					)
					(width 0)
					(fill yes)
				)
			)
		)
	)
	(footprint ""
		(layer "B.Cu")
		(at 93.599 -26.162 90)
		(property "Reference" "C245"
			(at 0 0 90)
			(layer "B.SilkS")
			(hide yes)
			(effects
				(font
					(size 1.27 1.27)
				)
				(justify mirror)
			)
		)
		(property "Value" "SC1U10V2KX-1GP"
			(at -1.1811 -2.7051 90)
			(unlocked yes)
			(layer "B.Fab")
			(hide yes)
			(effects
				(font
					(size 1.016 1.016)
					(thickness 0.1524)
				)
				(justify mirror)
			)
		)
		(property "Device Type" "C402H22"
			(at -1.1811 -4.2291 90)
			(unlocked yes)
			(layer "B.Fab")
			(hide yes)
			(effects
				(font
					(size 1.016 1.016)
					(thickness 0.1524)
				)
				(justify mirror)
			)
		)
		(duplicate_pad_numbers_are_jumpers no)
		(fp_rect
			(start 0.381 0.7366)
			(end -0.381 -0.7366)
			(stroke
				(width 0)
				(type default)
			)
			(fill no)
			(layer "B.CrtYd")
		)
		(fp_rect
			(start 0.381 0.7366)
			(end -0.381 -0.7366)
			(stroke
				(width 0)
				(type default)
			)
			(fill no)
			(layer "B.Fab")
		)
		(pad "1" smd custom
			(at 0 -0.4572 270)
			(size 0.1143 0.1143)
			(layers "B.Cu" "B.Mask" "B.Paste")
			(net "P1V0")
			(options
				(clearance outline)
				(anchor circle)
			)
			(primitives
				(gr_poly
					(pts
						(arc
							(start -0.254 0.1778)
							(mid -0.239121 0.213721)
							(end -0.2032 0.2286)
						)
						(arc
							(start 0.2032 0.2286)
							(mid 0.239121 0.213721)
							(end 0.254 0.1778)
						)
						(arc
							(start 0.254 -0.1778)
							(mid 0.239121 -0.213721)
							(end 0.2032 -0.2286)
						)
						(arc
							(start -0.2032 -0.2286)
							(mid -0.239121 -0.213721)
							(end -0.254 -0.1778)
						)
					)
					(width 0)
					(fill yes)
				)
			)
		)
		(pad "2" smd custom
			(at 0 0.4572 270)
			(size 0.1143 0.1143)
			(layers "B.Cu" "B.Mask" "B.Paste")
			(net "GND")
			(options
				(clearance outline)
				(anchor circle)
			)
			(primitives
				(gr_poly
					(pts
						(arc
							(start -0.254 0.1778)
							(mid -0.239121 0.213721)
							(end -0.2032 0.2286)
						)
						(arc
							(start 0.2032 0.2286)
							(mid 0.239121 0.213721)
							(end 0.254 0.1778)
						)
						(arc
							(start 0.254 -0.1778)
							(mid 0.239121 -0.213721)
							(end 0.2032 -0.2286)
						)
						(arc
							(start -0.2032 -0.2286)
							(mid -0.239121 -0.213721)
							(end -0.254 -0.1778)
						)
					)
					(width 0)
					(fill yes)
				)
			)
		)
	)
	(footprint ""
		(layer "B.Cu")
		(at 73.152 -50.673 -90)
		(property "Reference" "R263"
			(at 0 0 90)
			(layer "B.SilkS")
			(hide yes)
			(effects
				(font
					(size 1.27 1.27)
				)
				(justify mirror)
			)
		)
		(property "Value" "330R2F-GP"
			(at -0.064008 -3.993896 270)
			(unlocked yes)
			(layer "B.Fab")
			(hide yes)
			(effects
				(font
					(size 1.016 1.016)
					(thickness 0.1524)
				)
				(justify mirror)
			)
		)
		(property "Device Type" "R402H16"
			(at -0.064008 -5.517896 270)
			(unlocked yes)
			(layer "B.Fab")
			(hide yes)
			(effects
				(font
					(size 1.016 1.016)
					(thickness 0.1524)
				)
				(justify mirror)
			)
		)
		(duplicate_pad_numbers_are_jumpers no)
		(fp_rect
			(start 0.381 0.8382)
			(end -0.381 -0.8382)
			(stroke
				(width 0)
				(type default)
			)
			(fill no)
			(layer "B.CrtYd")
		)
		(fp_rect
			(start 0.381 0.8382)
			(end -0.381 -0.8382)
			(stroke
				(width 0)
				(type default)
			)
			(fill no)
			(layer "B.Fab")
		)
		(pad "1" smd custom
			(at 0 -0.4318 90)
			(size 0.127 0.127)
			(layers "B.Cu" "B.Mask" "B.Paste")
			(net "P1V0")
			(options
				(clearance outline)
				(anchor circle)
			)
			(primitives
				(gr_poly
					(pts
						(arc
							(start -0.2032 0.2794)
							(mid -0.239121 0.264521)
							(end -0.254 0.2286)
						)
						(arc
							(start -0.254 -0.2286)
							(mid -0.239121 -0.264521)
							(end -0.2032 -0.2794)
						)
						(arc
							(start 0.2032 -0.2794)
							(mid 0.239121 -0.264521)
							(end 0.254 -0.2286)
						)
						(arc
							(start 0.254 0.2286)
							(mid 0.239121 0.264521)
							(end 0.2032 0.2794)
						)
					)
					(width 0)
					(fill yes)
				)
			)
		)
		(pad "2" smd custom
			(at 0 0.4318 90)
			(size 0.127 0.127)
			(layers "B.Cu" "B.Mask" "B.Paste")
			(net "MEMORY_HOT_N_LV_B1")
			(options
				(clearance outline)
				(anchor circle)
			)
			(primitives
				(gr_poly
					(pts
						(arc
							(start -0.2032 0.2794)
							(mid -0.239121 0.264521)
							(end -0.254 0.2286)
						)
						(arc
							(start -0.254 -0.2286)
							(mid -0.239121 -0.264521)
							(end -0.2032 -0.2794)
						)
						(arc
							(start 0.2032 -0.2794)
							(mid 0.239121 -0.264521)
							(end 0.254 -0.2286)
						)
						(arc
							(start 0.254 0.2286)
							(mid 0.239121 0.264521)
							(end 0.2032 0.2794)
						)
					)
					(width 0)
					(fill yes)
				)
			)
		)
	)
	(footprint ""
		(layer "B.Cu")
		(at 119.38 -61.595 -90)
		(property "Reference" "C102"
			(at 0 0 90)
			(layer "B.SilkS")
			(hide yes)
			(effects
				(font
					(size 1.27 1.27)
				)
				(justify mirror)
			)
		)
		(property "Value" "SC1U6D3V2KX-GP"
			(at -1.1811 -2.7051 270)
			(unlocked yes)
			(layer "B.Fab")
			(hide yes)
			(effects
				(font
					(size 1.016 1.016)
					(thickness 0.1524)
				)
				(justify mirror)
			)
		)
		(property "Device Type" "C402H22"
			(at -1.1811 -4.2291 270)
			(unlocked yes)
			(layer "B.Fab")
			(hide yes)
			(effects
				(font
					(size 1.016 1.016)
					(thickness 0.1524)
				)
				(justify mirror)
			)
		)
		(duplicate_pad_numbers_are_jumpers no)
		(fp_rect
			(start 0.381 0.7366)
			(end -0.381 -0.7366)
			(stroke
				(width 0)
				(type default)
			)
			(fill no)
			(layer "B.CrtYd")
		)
		(fp_rect
			(start 0.381 0.7366)
			(end -0.381 -0.7366)
			(stroke
				(width 0)
				(type default)
			)
			(fill no)
			(layer "B.Fab")
		)
		(pad "1" smd custom
			(at 0 -0.4572 90)
			(size 0.1143 0.1143)
			(layers "B.Cu" "B.Mask" "B.Paste")
			(net "PV_VTT_DDR_A")
			(options
				(clearance outline)
				(anchor circle)
			)
			(primitives
				(gr_poly
					(pts
						(arc
							(start -0.254 0.1778)
							(mid -0.239121 0.213721)
							(end -0.2032 0.2286)
						)
						(arc
							(start 0.2032 0.2286)
							(mid 0.239121 0.213721)
							(end 0.254 0.1778)
						)
						(arc
							(start 0.254 -0.1778)
							(mid 0.239121 -0.213721)
							(end 0.2032 -0.2286)
						)
						(arc
							(start -0.2032 -0.2286)
							(mid -0.239121 -0.213721)
							(end -0.254 -0.1778)
						)
					)
					(width 0)
					(fill yes)
				)
			)
		)
		(pad "2" smd custom
			(at 0 0.4572 90)
			(size 0.1143 0.1143)
			(layers "B.Cu" "B.Mask" "B.Paste")
			(net "GND")
			(options
				(clearance outline)
				(anchor circle)
			)
			(primitives
				(gr_poly
					(pts
						(arc
							(start -0.254 0.1778)
							(mid -0.239121 0.213721)
							(end -0.2032 0.2286)
						)
						(arc
							(start 0.2032 0.2286)
							(mid 0.239121 0.213721)
							(end 0.254 0.1778)
						)
						(arc
							(start 0.254 -0.1778)
							(mid 0.239121 -0.213721)
							(end 0.2032 -0.2286)
						)
						(arc
							(start -0.2032 -0.2286)
							(mid -0.239121 -0.213721)
							(end -0.254 -0.1778)
						)
					)
					(width 0)
					(fill yes)
				)
			)
		)
	)
	(footprint ""
		(layer "B.Cu")
		(at 104.14 -31.766002 180)
		(property "Reference" "R356"
			(at 0 0 0)
			(layer "B.SilkS")
			(hide yes)
			(effects
				(font
					(size 1.27 1.27)
				)
				(justify mirror)
			)
		)
		(property "Value" "1KR2F-3-GP"
			(at -0.064008 -3.993896 180)
			(unlocked yes)
			(layer "B.Fab")
			(hide yes)
			(effects
				(font
					(size 1.016 1.016)
					(thickness 0.1524)
				)
				(justify mirror)
			)
		)
		(property "Device Type" "R402H16"
			(at -0.064008 -5.517896 180)
			(unlocked yes)
			(layer "B.Fab")
			(hide yes)
			(effects
				(font
					(size 1.016 1.016)
					(thickness 0.1524)
				)
				(justify mirror)
			)
		)
		(duplicate_pad_numbers_are_jumpers no)
		(fp_rect
			(start 0.381 0.8382)
			(end -0.381 -0.8382)
			(stroke
				(width 0)
				(type default)
			)
			(fill no)
			(layer "B.CrtYd")
		)
		(fp_rect
			(start 0.381 0.8382)
			(end -0.381 -0.8382)
			(stroke
				(width 0)
				(type default)
			)
			(fill no)
			(layer "B.Fab")
		)
		(pad "1" smd custom
			(at 0 -0.4318)
			(size 0.127 0.127)
			(layers "B.Cu" "B.Mask" "B.Paste")
			(net "PV_VDDR")
			(options
				(clearance outline)
				(anchor circle)
			)
			(primitives
				(gr_poly
					(pts
						(arc
							(start -0.2032 0.2794)
							(mid -0.239121 0.264521)
							(end -0.254 0.2286)
						)
						(arc
							(start -0.254 -0.2286)
							(mid -0.239121 -0.264521)
							(end -0.2032 -0.2794)
						)
						(arc
							(start 0.2032 -0.2794)
							(mid 0.239121 -0.264521)
							(end 0.254 -0.2286)
						)
						(arc
							(start 0.254 0.2286)
							(mid 0.239121 0.264521)
							(end 0.2032 0.2794)
						)
					)
					(width 0)
					(fill yes)
				)
			)
		)
		(pad "2" smd custom
			(at 0 0.4318)
			(size 0.127 0.127)
			(layers "B.Cu" "B.Mask" "B.Paste")
			(net "PWRGD_DDR3_VCCA")
			(options
				(clearance outline)
				(anchor circle)
			)
			(primitives
				(gr_poly
					(pts
						(arc
							(start -0.2032 0.2794)
							(mid -0.239121 0.264521)
							(end -0.254 0.2286)
						)
						(arc
							(start -0.254 -0.2286)
							(mid -0.239121 -0.264521)
							(end -0.2032 -0.2794)
						)
						(arc
							(start 0.2032 -0.2794)
							(mid 0.239121 -0.264521)
							(end 0.254 -0.2286)
						)
						(arc
							(start 0.254 0.2286)
							(mid 0.239121 0.264521)
							(end 0.2032 0.2794)
						)
					)
					(width 0)
					(fill yes)
				)
			)
		)
	)
	(footprint ""
		(layer "B.Cu")
		(at 32.385 -25.273 180)
		(property "Reference" "PR102"
			(at 0 0 0)
			(layer "B.SilkS")
			(hide yes)
			(effects
				(font
					(size 1.27 1.27)
				)
				(justify mirror)
			)
		)
		(property "Value" "10D7R2F-GP"
			(at -1.7907 -1.1176 180)
			(unlocked yes)
			(layer "B.Fab")
			(hide yes)
			(effects
				(font
					(size 1.016 1.016)
					(thickness 0.1524)
				)
				(justify mirror)
			)
		)
		(property "Device Type" "R402H16"
			(at -1.7907 -2.6416 180)
			(unlocked yes)
			(layer "B.Fab")
			(hide yes)
			(effects
				(font
					(size 1.016 1.016)
					(thickness 0.1524)
				)
				(justify mirror)
			)
		)
		(duplicate_pad_numbers_are_jumpers no)
		(fp_rect
			(start 0.381 0.8382)
			(end -0.381 -0.8382)
			(stroke
				(width 0)
				(type default)
			)
			(fill no)
			(layer "B.CrtYd")
		)
		(fp_rect
			(start 0.381 0.8382)
			(end -0.381 -0.8382)
			(stroke
				(width 0)
				(type default)
			)
			(fill no)
			(layer "B.Fab")
		)
		(pad "1" smd custom
			(at 0 -0.4318)
			(size 0.127 0.127)
			(layers "B.Cu" "B.Mask" "B.Paste")
			(net "P1V0_VFB_R")
			(options
				(clearance outline)
				(anchor circle)
			)
			(primitives
				(gr_poly
					(pts
						(arc
							(start -0.2032 0.2794)
							(mid -0.239121 0.264521)
							(end -0.254 0.2286)
						)
						(arc
							(start -0.254 -0.2286)
							(mid -0.239121 -0.264521)
							(end -0.2032 -0.2794)
						)
						(arc
							(start 0.2032 -0.2794)
							(mid 0.239121 -0.264521)
							(end 0.254 -0.2286)
						)
						(arc
							(start 0.254 0.2286)
							(mid 0.239121 0.264521)
							(end 0.2032 0.2794)
						)
					)
					(width 0)
					(fill yes)
				)
			)
		)
		(pad "2" smd custom
			(at 0 0.4318)
			(size 0.127 0.127)
			(layers "B.Cu" "B.Mask" "B.Paste")
			(net "P1V0")
			(options
				(clearance outline)
				(anchor circle)
			)
			(primitives
				(gr_poly
					(pts
						(arc
							(start -0.2032 0.2794)
							(mid -0.239121 0.264521)
							(end -0.254 0.2286)
						)
						(arc
							(start -0.254 -0.2286)
							(mid -0.239121 -0.264521)
							(end -0.2032 -0.2794)
						)
						(arc
							(start 0.2032 -0.2794)
							(mid 0.239121 -0.264521)
							(end 0.254 -0.2286)
						)
						(arc
							(start 0.254 0.2286)
							(mid 0.239121 0.264521)
							(end 0.2032 0.2794)
						)
					)
					(width 0)
					(fill yes)
				)
			)
		)
	)
)
